(kicad_pcb
	(version 20260206)
	(generator "pcbnew")
	(generator_version "10.0")
	(general
		(thickness 1.6)
		(legacy_teardrops no)
	)
	(paper "A4")
	(title_block
		(title "04192023_DAF0TMB3IC0_F0TG_MB_C_brd_V02_OCP.brd")
		(comment 1 "Grand Teton / footprints 1615-1622 of 8354")
	)
	(layers
		(0 "F.Cu" signal "TOP")
		(4 "In1.Cu" signal "GND")
		(6 "In2.Cu" signal "IN1")
		(8 "In3.Cu" signal "GND1")
		(10 "In4.Cu" signal "IN2")
		(12 "In5.Cu" signal "GND2")
		(14 "In6.Cu" signal "IN3")
		(16 "In7.Cu" signal "GND3")
		(18 "In8.Cu" signal "VCC")
		(20 "In9.Cu" signal "VCC1")
		(22 "In10.Cu" signal "GND4")
		(24 "In11.Cu" signal "IN4")
		(26 "In12.Cu" signal "GND5")
		(28 "In13.Cu" signal "IN5")
		(30 "In14.Cu" signal "GND6")
		(32 "In15.Cu" signal "IN6")
		(34 "In16.Cu" signal "GND7")
		(2 "B.Cu" signal "BOTTOM")
		(9 "F.Adhes" user "F.Adhesive")
		(11 "B.Adhes" user "B.Adhesive")
		(13 "F.Paste" user "Package Geometry/Pastemask Top")
		(15 "B.Paste" user "Package Geometry/Pastemask Bottom")
		(5 "F.SilkS" user "Ref Des/Silkscreen Top")
		(7 "B.SilkS" user "Ref Des/Silkscreen Bottom")
		(1 "F.Mask" user "Board Geometry/Soldermask Top")
		(3 "B.Mask" user "Board Geometry/Soldermask Bottom")
		(17 "Dwgs.User" user "User.Drawings")
		(19 "Cmts.User" user "User.Comments")
		(21 "Eco1.User" user "User.Eco1")
		(23 "Eco2.User" user "User.Eco2")
		(25 "Edge.Cuts" user "Board Geometry/Outline")
		(27 "Margin" user)
		(31 "F.CrtYd" user "Package Geometry/Place Bound Top")
		(29 "B.CrtYd" user "Package Geometry/Place Bound Bottom")
		(35 "F.Fab" user "Ref Des/Assembly Top")
		(33 "B.Fab" user "Ref Des/Assembly Bottom")
	)
	(footprint ""
		(layer "F.Cu")
		(at 294.421052 -114.221514)
		(property "Reference" "R2704"
			(at 0 0 0)
			(layer "F.SilkS")
			(hide yes)
			(effects
				(font
					(size 1.27 1.27)
				)
			)
		)
		(property "Value" ""
			(at 0 0 0)
			(layer "F.Fab")
			(effects
				(font
					(size 1.27 1.27)
				)
			)
		)
		(duplicate_pad_numbers_are_jumpers no)
		(fp_line
			(start -0.7874 -0.4064)
			(end 0.7874 -0.4064)
			(stroke
				(width 0.1524)
				(type default)
			)
			(layer "F.SilkS")
		)
		(fp_line
			(start -0.7874 0.4064)
			(end -0.7874 -0.4064)
			(stroke
				(width 0.1524)
				(type default)
			)
			(layer "F.SilkS")
		)
		(fp_line
			(start 0.7874 -0.4064)
			(end 0.7874 0.4064)
			(stroke
				(width 0.1524)
				(type default)
			)
			(layer "F.SilkS")
		)
		(fp_line
			(start 0.7874 0.4064)
			(end -0.7874 0.4064)
			(stroke
				(width 0.1524)
				(type default)
			)
			(layer "F.SilkS")
		)
		(fp_line
			(start -0.67945 -0.305054)
			(end -0.12065 -0.305054)
			(stroke
				(width 0.1)
				(type default)
			)
			(layer "F.Fab")
		)
		(fp_line
			(start -0.67945 0.3048)
			(end -0.67945 -0.305054)
			(stroke
				(width 0.1)
				(type default)
			)
			(layer "F.Fab")
		)
		(fp_line
			(start -0.12065 -0.305054)
			(end -0.12065 -0.2794)
			(stroke
				(width 0.1)
				(type default)
			)
			(layer "F.Fab")
		)
		(fp_line
			(start -0.12065 -0.2794)
			(end 0.12065 -0.2794)
			(stroke
				(width 0.1)
				(type default)
			)
			(layer "F.Fab")
		)
		(fp_line
			(start -0.12065 0.2794)
			(end -0.12065 0.3048)
			(stroke
				(width 0.1)
				(type default)
			)
			(layer "F.Fab")
		)
		(fp_line
			(start -0.12065 0.3048)
			(end -0.67945 0.3048)
			(stroke
				(width 0.1)
				(type default)
			)
			(layer "F.Fab")
		)
		(fp_line
			(start 0.120396 0.2794)
			(end -0.12065 0.2794)
			(stroke
				(width 0.1)
				(type default)
			)
			(layer "F.Fab")
		)
		(fp_line
			(start 0.120396 0.3048)
			(end 0.120396 0.2794)
			(stroke
				(width 0.1)
				(type default)
			)
			(layer "F.Fab")
		)
		(fp_line
			(start 0.12065 -0.3048)
			(end 0.67945 -0.3048)
			(stroke
				(width 0.1)
				(type default)
			)
			(layer "F.Fab")
		)
		(fp_line
			(start 0.12065 -0.2794)
			(end 0.12065 -0.3048)
			(stroke
				(width 0.1)
				(type default)
			)
			(layer "F.Fab")
		)
		(fp_line
			(start 0.67945 -0.3048)
			(end 0.67945 0.3048)
			(stroke
				(width 0.1)
				(type default)
			)
			(layer "F.Fab")
		)
		(fp_line
			(start 0.67945 0.3048)
			(end 0.120396 0.3048)
			(stroke
				(width 0.1)
				(type default)
			)
			(layer "F.Fab")
		)
		(pad "1" smd circle
			(at -0.40005 0)
			(size 0 0)
			(layers "F.Cu" "F.Mask" "F.Paste")
			(net "SMB_BMC_SWB_SDA_R4")
		)
		(pad "2" smd circle
			(at 0.40005 0)
			(size 0 0)
			(layers "F.Cu" "F.Mask" "F.Paste")
			(net "SMB_BMC_SWB_SDA")
		)
	)
	(footprint ""
		(layer "F.Cu")
		(at 66.148204 -408.517344 -90)
		(property "Reference" "C6642"
			(at 0 0 270)
			(layer "F.SilkS")
			(hide yes)
			(effects
				(font
					(size 1.27 1.27)
				)
			)
		)
		(property "Value" ""
			(at 0 0 270)
			(layer "F.Fab")
			(effects
				(font
					(size 1.27 1.27)
				)
			)
		)
		(duplicate_pad_numbers_are_jumpers no)
		(fp_line
			(start -0.299974 0.150114)
			(end -0.299974 -0.150114)
			(stroke
				(width 0.1)
				(type default)
			)
			(layer "F.Fab")
		)
		(fp_line
			(start 0.299974 0.150114)
			(end -0.299974 0.150114)
			(stroke
				(width 0.1)
				(type default)
			)
			(layer "F.Fab")
		)
		(fp_line
			(start -0.299974 -0.150114)
			(end 0.299974 -0.150114)
			(stroke
				(width 0.1)
				(type default)
			)
			(layer "F.Fab")
		)
		(fp_line
			(start 0.299974 -0.150114)
			(end 0.299974 0.150114)
			(stroke
				(width 0.1)
				(type default)
			)
			(layer "F.Fab")
		)
		(pad "1" smd rect
			(at -0.2667 0 270)
			(size 0.3048 0.381)
			(layers "F.Cu" "F.Mask" "F.Paste")
			(net "P5E_CPU1_P0_TX_BUF_C_DN<6>")
		)
		(pad "2" smd rect
			(at 0.2667 0 270)
			(size 0.3048 0.381)
			(layers "F.Cu" "F.Mask" "F.Paste")
			(net "P5E_CPU1_P0_TX_BUF_DN<6>")
		)
	)
	(footprint ""
		(layer "F.Cu")
		(at 225.899472 -290.341812 90)
		(property "Reference" "PC6534"
			(at 0 0 90)
			(layer "F.SilkS")
			(hide yes)
			(effects
				(font
					(size 1.27 1.27)
				)
			)
		)
		(property "Value" ""
			(at 0 0 90)
			(layer "F.Fab")
			(effects
				(font
					(size 1.27 1.27)
				)
			)
		)
		(duplicate_pad_numbers_are_jumpers no)
		(fp_line
			(start 0.7874 -0.4064)
			(end 0.7874 0.4064)
			(stroke
				(width 0.1524)
				(type default)
			)
			(layer "F.SilkS")
		)
		(fp_line
			(start -0.7874 -0.4064)
			(end 0.7874 -0.4064)
			(stroke
				(width 0.1524)
				(type default)
			)
			(layer "F.SilkS")
		)
		(fp_line
			(start 0.7874 0.4064)
			(end -0.7874 0.4064)
			(stroke
				(width 0.1524)
				(type default)
			)
			(layer "F.SilkS")
		)
		(fp_line
			(start -0.7874 0.4064)
			(end -0.7874 -0.4064)
			(stroke
				(width 0.1524)
				(type default)
			)
			(layer "F.SilkS")
		)
		(fp_line
			(start -0.12065 -0.305054)
			(end -0.12065 -0.2794)
			(stroke
				(width 0.1)
				(type default)
			)
			(layer "F.Fab")
		)
		(fp_line
			(start -0.67945 -0.305054)
			(end -0.12065 -0.305054)
			(stroke
				(width 0.1)
				(type default)
			)
			(layer "F.Fab")
		)
		(fp_line
			(start 0.67945 -0.3048)
			(end 0.67945 0.3048)
			(stroke
				(width 0.1)
				(type default)
			)
			(layer "F.Fab")
		)
		(fp_line
			(start 0.12065 -0.3048)
			(end 0.67945 -0.3048)
			(stroke
				(width 0.1)
				(type default)
			)
			(layer "F.Fab")
		)
		(fp_line
			(start 0.12065 -0.2794)
			(end 0.12065 -0.3048)
			(stroke
				(width 0.1)
				(type default)
			)
			(layer "F.Fab")
		)
		(fp_line
			(start -0.12065 -0.2794)
			(end 0.12065 -0.2794)
			(stroke
				(width 0.1)
				(type default)
			)
			(layer "F.Fab")
		)
		(fp_line
			(start 0.120396 0.2794)
			(end -0.12065 0.2794)
			(stroke
				(width 0.1)
				(type default)
			)
			(layer "F.Fab")
		)
		(fp_line
			(start -0.12065 0.2794)
			(end -0.12065 0.3048)
			(stroke
				(width 0.1)
				(type default)
			)
			(layer "F.Fab")
		)
		(fp_line
			(start 0.67945 0.3048)
			(end 0.120396 0.3048)
			(stroke
				(width 0.1)
				(type default)
			)
			(layer "F.Fab")
		)
		(fp_line
			(start 0.120396 0.3048)
			(end 0.120396 0.2794)
			(stroke
				(width 0.1)
				(type default)
			)
			(layer "F.Fab")
		)
		(fp_line
			(start -0.12065 0.3048)
			(end -0.67945 0.3048)
			(stroke
				(width 0.1)
				(type default)
			)
			(layer "F.Fab")
		)
		(fp_line
			(start -0.67945 0.3048)
			(end -0.67945 -0.305054)
			(stroke
				(width 0.1)
				(type default)
			)
			(layer "F.Fab")
		)
		(pad "1" smd circle
			(at -0.40005 0 90)
			(size 0 0)
			(layers "F.Cu" "F.Mask" "F.Paste")
			(net "P1V8_RETIMER_CPU1_FB")
		)
		(pad "2" smd circle
			(at 0.40005 0 90)
			(size 0 0)
			(layers "F.Cu" "F.Mask" "F.Paste")
			(net "P1V8_CPU1_RT_1D")
		)
	)
	(footprint ""
		(layer "F.Cu")
		(at 113.684304 -418.079428 -90)
		(property "Reference" "R3510"
			(at 0 0 270)
			(layer "F.SilkS")
			(hide yes)
			(effects
				(font
					(size 1.27 1.27)
				)
			)
		)
		(property "Value" ""
			(at 0 0 270)
			(layer "F.Fab")
			(effects
				(font
					(size 1.27 1.27)
				)
			)
		)
		(duplicate_pad_numbers_are_jumpers no)
		(fp_line
			(start -0.7874 0.4064)
			(end -0.7874 -0.4064)
			(stroke
				(width 0.1524)
				(type default)
			)
			(layer "F.SilkS")
		)
		(fp_line
			(start 0.7874 0.4064)
			(end -0.7874 0.4064)
			(stroke
				(width 0.1524)
				(type default)
			)
			(layer "F.SilkS")
		)
		(fp_line
			(start -0.7874 -0.4064)
			(end 0.7874 -0.4064)
			(stroke
				(width 0.1524)
				(type default)
			)
			(layer "F.SilkS")
		)
		(fp_line
			(start 0.7874 -0.4064)
			(end 0.7874 0.4064)
			(stroke
				(width 0.1524)
				(type default)
			)
			(layer "F.SilkS")
		)
		(fp_line
			(start -0.67945 0.3048)
			(end -0.67945 -0.305054)
			(stroke
				(width 0.1)
				(type default)
			)
			(layer "F.Fab")
		)
		(fp_line
			(start -0.12065 0.3048)
			(end -0.67945 0.3048)
			(stroke
				(width 0.1)
				(type default)
			)
			(layer "F.Fab")
		)
		(fp_line
			(start 0.120396 0.3048)
			(end 0.120396 0.2794)
			(stroke
				(width 0.1)
				(type default)
			)
			(layer "F.Fab")
		)
		(fp_line
			(start 0.67945 0.3048)
			(end 0.120396 0.3048)
			(stroke
				(width 0.1)
				(type default)
			)
			(layer "F.Fab")
		)
		(fp_line
			(start -0.12065 0.2794)
			(end -0.12065 0.3048)
			(stroke
				(width 0.1)
				(type default)
			)
			(layer "F.Fab")
		)
		(fp_line
			(start 0.120396 0.2794)
			(end -0.12065 0.2794)
			(stroke
				(width 0.1)
				(type default)
			)
			(layer "F.Fab")
		)
		(fp_line
			(start -0.12065 -0.2794)
			(end 0.12065 -0.2794)
			(stroke
				(width 0.1)
				(type default)
			)
			(layer "F.Fab")
		)
		(fp_line
			(start 0.12065 -0.2794)
			(end 0.12065 -0.3048)
			(stroke
				(width 0.1)
				(type default)
			)
			(layer "F.Fab")
		)
		(fp_line
			(start 0.12065 -0.3048)
			(end 0.67945 -0.3048)
			(stroke
				(width 0.1)
				(type default)
			)
			(layer "F.Fab")
		)
		(fp_line
			(start 0.67945 -0.3048)
			(end 0.67945 0.3048)
			(stroke
				(width 0.1)
				(type default)
			)
			(layer "F.Fab")
		)
		(fp_line
			(start -0.67945 -0.305054)
			(end -0.12065 -0.305054)
			(stroke
				(width 0.1)
				(type default)
			)
			(layer "F.Fab")
		)
		(fp_line
			(start -0.12065 -0.305054)
			(end -0.12065 -0.2794)
			(stroke
				(width 0.1)
				(type default)
			)
			(layer "F.Fab")
		)
		(pad "1" smd circle
			(at -0.40005 0 270)
			(size 0 0)
			(layers "F.Cu" "F.Mask" "F.Paste")
			(net "P3V3_AUX")
		)
		(pad "2" smd circle
			(at 0.40005 0 270)
			(size 0 0)
			(layers "F.Cu" "F.Mask" "F.Paste")
			(net "FM_SMB_1_ALERT_GPU_N")
		)
	)
	(footprint ""
		(layer "F.Cu")
		(at 392.797284 -399.12798)
		(property "Reference" "R1408"
			(at 0 0 0)
			(layer "F.SilkS")
			(hide yes)
			(effects
				(font
					(size 1.27 1.27)
				)
			)
		)
		(property "Value" ""
			(at 0 0 0)
			(layer "F.Fab")
			(effects
				(font
					(size 1.27 1.27)
				)
			)
		)
		(duplicate_pad_numbers_are_jumpers no)
		(fp_line
			(start -0.32512 -0.175006)
			(end 0.32512 -0.175006)
			(stroke
				(width 0.1)
				(type default)
			)
			(layer "F.Fab")
		)
		(fp_line
			(start -0.32512 0.175006)
			(end -0.32512 -0.175006)
			(stroke
				(width 0.1)
				(type default)
			)
			(layer "F.Fab")
		)
		(fp_line
			(start 0.32512 -0.175006)
			(end 0.32512 0.175006)
			(stroke
				(width 0.1)
				(type default)
			)
			(layer "F.Fab")
		)
		(fp_line
			(start 0.32512 0.175006)
			(end -0.32512 0.175006)
			(stroke
				(width 0.1)
				(type default)
			)
			(layer "F.Fab")
		)
		(pad "1" smd rect
			(at -0.2667 0)
			(size 0.3048 0.381)
			(layers "F.Cu" "F.Mask" "F.Paste")
			(net "JTAG_TRST_RT_CPU0_P3_N")
		)
		(pad "2" smd rect
			(at 0.2667 0 180)
			(size 0.3048 0.381)
			(layers "F.Cu" "F.Mask" "F.Paste")
			(net "GND")
		)
	)
	(footprint ""
		(layer "F.Cu")
		(at 323.513958 -193.925952 -90)
		(property "Reference" "R412"
			(at 0 0 270)
			(layer "F.SilkS")
			(hide yes)
			(effects
				(font
					(size 1.27 1.27)
				)
			)
		)
		(property "Value" ""
			(at 0 0 270)
			(layer "F.Fab")
			(effects
				(font
					(size 1.27 1.27)
				)
			)
		)
		(duplicate_pad_numbers_are_jumpers no)
		(fp_line
			(start -0.7874 0.4064)
			(end -0.7874 -0.4064)
			(stroke
				(width 0.1524)
				(type default)
			)
			(layer "F.SilkS")
		)
		(fp_line
			(start 0.7874 0.4064)
			(end -0.7874 0.4064)
			(stroke
				(width 0.1524)
				(type default)
			)
			(layer "F.SilkS")
		)
		(fp_line
			(start -0.7874 -0.4064)
			(end 0.7874 -0.4064)
			(stroke
				(width 0.1524)
				(type default)
			)
			(layer "F.SilkS")
		)
		(fp_line
			(start 0.7874 -0.4064)
			(end 0.7874 0.4064)
			(stroke
				(width 0.1524)
				(type default)
			)
			(layer "F.SilkS")
		)
		(fp_line
			(start -0.67945 0.3048)
			(end -0.67945 -0.305054)
			(stroke
				(width 0.1)
				(type default)
			)
			(layer "F.Fab")
		)
		(fp_line
			(start -0.12065 0.3048)
			(end -0.67945 0.3048)
			(stroke
				(width 0.1)
				(type default)
			)
			(layer "F.Fab")
		)
		(fp_line
			(start 0.120396 0.3048)
			(end 0.120396 0.2794)
			(stroke
				(width 0.1)
				(type default)
			)
			(layer "F.Fab")
		)
		(fp_line
			(start 0.67945 0.3048)
			(end 0.120396 0.3048)
			(stroke
				(width 0.1)
				(type default)
			)
			(layer "F.Fab")
		)
		(fp_line
			(start -0.12065 0.2794)
			(end -0.12065 0.3048)
			(stroke
				(width 0.1)
				(type default)
			)
			(layer "F.Fab")
		)
		(fp_line
			(start 0.120396 0.2794)
			(end -0.12065 0.2794)
			(stroke
				(width 0.1)
				(type default)
			)
			(layer "F.Fab")
		)
		(fp_line
			(start -0.12065 -0.2794)
			(end 0.12065 -0.2794)
			(stroke
				(width 0.1)
				(type default)
			)
			(layer "F.Fab")
		)
		(fp_line
			(start 0.12065 -0.2794)
			(end 0.12065 -0.3048)
			(stroke
				(width 0.1)
				(type default)
			)
			(layer "F.Fab")
		)
		(fp_line
			(start 0.12065 -0.3048)
			(end 0.67945 -0.3048)
			(stroke
				(width 0.1)
				(type default)
			)
			(layer "F.Fab")
		)
		(fp_line
			(start 0.67945 -0.3048)
			(end 0.67945 0.3048)
			(stroke
				(width 0.1)
				(type default)
			)
			(layer "F.Fab")
		)
		(fp_line
			(start -0.67945 -0.305054)
			(end -0.12065 -0.305054)
			(stroke
				(width 0.1)
				(type default)
			)
			(layer "F.Fab")
		)
		(fp_line
			(start -0.12065 -0.305054)
			(end -0.12065 -0.2794)
			(stroke
				(width 0.1)
				(type default)
			)
			(layer "F.Fab")
		)
		(pad "1" smd circle
			(at -0.40005 0 270)
			(size 0 0)
			(layers "F.Cu" "F.Mask" "F.Paste")
			(net "CPU0_PROCHOT_N")
		)
		(pad "2" smd circle
			(at 0.40005 0 270)
			(size 0 0)
			(layers "F.Cu" "F.Mask" "F.Paste")
			(net "PVDD18_S5_P0")
		)
	)
	(footprint ""
		(layer "F.Cu")
		(at 280.008584 -343.712038 180)
		(property "Reference" "PC166"
			(at 0 0 180)
			(layer "F.SilkS")
			(hide yes)
			(effects
				(font
					(size 1.27 1.27)
				)
			)
		)
		(property "Value" ""
			(at 0 0 180)
			(layer "F.Fab")
			(effects
				(font
					(size 1.27 1.27)
				)
			)
		)
		(duplicate_pad_numbers_are_jumpers no)
		(fp_line
			(start 0.7874 0.4064)
			(end -0.7874 0.4064)
			(stroke
				(width 0.1524)
				(type default)
			)
			(layer "F.SilkS")
		)
		(fp_line
			(start 0.7874 -0.4064)
			(end 0.7874 0.4064)
			(stroke
				(width 0.1524)
				(type default)
			)
			(layer "F.SilkS")
		)
		(fp_line
			(start -0.7874 0.4064)
			(end -0.7874 -0.4064)
			(stroke
				(width 0.1524)
				(type default)
			)
			(layer "F.SilkS")
		)
		(fp_line
			(start -0.7874 -0.4064)
			(end 0.7874 -0.4064)
			(stroke
				(width 0.1524)
				(type default)
			)
			(layer "F.SilkS")
		)
		(fp_line
			(start 0.67945 0.3048)
			(end 0.120396 0.3048)
			(stroke
				(width 0.1)
				(type default)
			)
			(layer "F.Fab")
		)
		(fp_line
			(start 0.67945 -0.3048)
			(end 0.67945 0.3048)
			(stroke
				(width 0.1)
				(type default)
			)
			(layer "F.Fab")
		)
		(fp_line
			(start 0.12065 -0.2794)
			(end 0.12065 -0.3048)
			(stroke
				(width 0.1)
				(type default)
			)
			(layer "F.Fab")
		)
		(fp_line
			(start 0.12065 -0.3048)
			(end 0.67945 -0.3048)
			(stroke
				(width 0.1)
				(type default)
			)
			(layer "F.Fab")
		)
		(fp_line
			(start 0.120396 0.3048)
			(end 0.120396 0.2794)
			(stroke
				(width 0.1)
				(type default)
			)
			(layer "F.Fab")
		)
		(fp_line
			(start 0.120396 0.2794)
			(end -0.12065 0.2794)
			(stroke
				(width 0.1)
				(type default)
			)
			(layer "F.Fab")
		)
		(fp_line
			(start -0.12065 0.3048)
			(end -0.67945 0.3048)
			(stroke
				(width 0.1)
				(type default)
			)
			(layer "F.Fab")
		)
		(fp_line
			(start -0.12065 0.2794)
			(end -0.12065 0.3048)
			(stroke
				(width 0.1)
				(type default)
			)
			(layer "F.Fab")
		)
		(fp_line
			(start -0.12065 -0.2794)
			(end 0.12065 -0.2794)
			(stroke
				(width 0.1)
				(type default)
			)
			(layer "F.Fab")
		)
		(fp_line
			(start -0.12065 -0.305054)
			(end -0.12065 -0.2794)
			(stroke
				(width 0.1)
				(type default)
			)
			(layer "F.Fab")
		)
		(fp_line
			(start -0.67945 0.3048)
			(end -0.67945 -0.305054)
			(stroke
				(width 0.1)
				(type default)
			)
			(layer "F.Fab")
		)
		(fp_line
			(start -0.67945 -0.305054)
			(end -0.12065 -0.305054)
			(stroke
				(width 0.1)
				(type default)
			)
			(layer "F.Fab")
		)
		(pad "1" smd circle
			(at -0.40005 0 180)
			(size 0 0)
			(layers "F.Cu" "F.Mask" "F.Paste")
			(net "SW_PVDDIO_P0_SW3")
		)
		(pad "2" smd circle
			(at 0.40005 0 180)
			(size 0 0)
			(layers "F.Cu" "F.Mask" "F.Paste")
			(net "SW_PVDDIO_P0_SW3_RC")
		)
	)
	(footprint ""
		(layer "F.Cu")
		(at 446.493392 -47.506382 -90)
		(property "Reference" "PC2260"
			(at 0 0 270)
			(layer "F.SilkS")
			(hide yes)
			(effects
				(font
					(size 1.27 1.27)
				)
			)
		)
		(property "Value" ""
			(at 0 0 270)
			(layer "F.Fab")
			(effects
				(font
					(size 1.27 1.27)
				)
			)
		)
		(duplicate_pad_numbers_are_jumpers no)
		(fp_line
			(start -1.524 0.762)
			(end -1.524 -0.762)
			(stroke
				(width 0.1524)
				(type default)
			)
			(layer "F.SilkS")
		)
		(fp_line
			(start 1.524 0.762)
			(end -1.524 0.762)
			(stroke
				(width 0.1524)
				(type default)
			)
			(layer "F.SilkS")
		)
		(fp_line
			(start -1.524 -0.762)
			(end 1.524 -0.762)
			(stroke
				(width 0.1524)
				(type default)
			)
			(layer "F.SilkS")
		)
		(fp_line
			(start 1.524 -0.762)
			(end 1.524 0.762)
			(stroke
				(width 0.1524)
				(type default)
			)
			(layer "F.SilkS")
		)
		(fp_line
			(start -1.1049 0.724916)
			(end 1.1049 0.724916)
			(stroke
				(width 0.1)
				(type default)
			)
			(layer "F.Fab")
		)
		(fp_line
			(start 1.1049 0.724916)
			(end 1.1049 -0.724916)
			(stroke
				(width 0.1)
				(type default)
			)
			(layer "F.Fab")
		)
		(fp_line
			(start -1.1049 -0.724916)
			(end -1.1049 0.724916)
			(stroke
				(width 0.1)
				(type default)
			)
			(layer "F.Fab")
		)
		(fp_line
			(start 1.1049 -0.724916)
			(end -1.1049 -0.724916)
			(stroke
				(width 0.1)
				(type default)
			)
			(layer "F.Fab")
		)
		(pad "1" smd rect
			(at -0.889 0 90)
			(size 1.016 1.27)
			(layers "F.Cu" "F.Mask" "F.Paste")
			(net "SW_P3V3_AUX_FLT")
		)
		(pad "2" smd rect
			(at 0.889 0 90)
			(size 1.016 1.27)
			(layers "F.Cu" "F.Mask" "F.Paste")
			(net "GND")
		)
	)
)
